(kicad_pcb
	(version 20260206)
	(generator "pcbnew")
	(generator_version "10.0")
	(general
		(thickness 1.6)
		(legacy_teardrops no)
	)
	(paper "A4")
	(title_block
		(title "Wiwynn_Tioga_Pass_MB.brd")
		(comment 1 "Tioga Pass / footprints 1072-1077 of 4770")
	)
	(layers
		(0 "F.Cu" signal "TOP")
		(4 "In1.Cu" signal "L2GND")
		(6 "In2.Cu" signal "L3")
		(8 "In3.Cu" signal "L4GND")
		(10 "In4.Cu" signal "L5")
		(12 "In5.Cu" signal "L6GND")
		(14 "In6.Cu" signal "L7VCC")
		(16 "In7.Cu" signal "L8VCC")
		(18 "In8.Cu" signal "L9GND")
		(20 "In9.Cu" signal "L10")
		(22 "In10.Cu" signal "L11GND")
		(24 "In11.Cu" signal "L12")
		(26 "In12.Cu" signal "L13GND")
		(2 "B.Cu" signal "BOTTOM")
		(9 "F.Adhes" user "F.Adhesive")
		(11 "B.Adhes" user "B.Adhesive")
		(13 "F.Paste" user "Package Geometry/Pastemask Top")
		(15 "B.Paste" user "Package Geometry/Pastemask Bottom")
		(5 "F.SilkS" user "Ref Des/Silkscreen Top")
		(7 "B.SilkS" user "Ref Des/Silkscreen Bottom")
		(1 "F.Mask" user "Board Geometry/Soldermask Top")
		(3 "B.Mask" user "Board Geometry/Soldermask Bottom")
		(17 "Dwgs.User" user "User.Drawings")
		(19 "Cmts.User" user "User.Comments")
		(21 "Eco1.User" user "User.Eco1")
		(23 "Eco2.User" user "User.Eco2")
		(25 "Edge.Cuts" user "Board Geometry/Outline")
		(27 "Margin" user)
		(31 "F.CrtYd" user "Package Geometry/Place Bound Top")
		(29 "B.CrtYd" user "Package Geometry/Place Bound Bottom")
		(35 "F.Fab" user "Ref Des/Assembly Top")
		(33 "B.Fab" user "Ref Des/Assembly Bottom")
	)
	(footprint ""
		(layer "F.Cu")
		(at 396.367 -85.09 180)
		(property "Reference" "R2N25"
			(at 0 0 180)
			(layer "F.SilkS")
			(hide yes)
			(effects
				(font
					(size 1.27 1.27)
				)
			)
		)
		(property "Value" ""
			(at 0 0 180)
			(layer "F.Fab")
			(effects
				(font
					(size 1.27 1.27)
				)
			)
		)
		(duplicate_pad_numbers_are_jumpers no)
		(fp_poly
			(pts
				(xy -0.2794 -0.1016) (xy 0.2794 -0.1016) (xy 0.2794 0.9906) (xy -0.2794 0.9906)
			)
			(stroke
				(width 0)
				(type default)
			)
			(fill no)
			(layer "F.CrtYd")
		)
		(fp_line
			(start 0.2794 0.9906)
			(end 0.2794 -0.1016)
			(stroke
				(width 0.1)
				(type default)
			)
			(layer "F.Fab")
		)
		(fp_line
			(start 0.2794 -0.1016)
			(end -0.2794 -0.1016)
			(stroke
				(width 0.1)
				(type default)
			)
			(layer "F.Fab")
		)
		(fp_line
			(start -0.2794 0.9906)
			(end 0.2794 0.9906)
			(stroke
				(width 0.1)
				(type default)
			)
			(layer "F.Fab")
		)
		(fp_line
			(start -0.2794 -0.1016)
			(end -0.2794 0.9906)
			(stroke
				(width 0.1)
				(type default)
			)
			(layer "F.Fab")
		)
		(pad "1" smd rect
			(at 0 0 180)
			(size 0.508 0.508)
			(layers "F.Cu" "F.Mask" "F.Paste")
			(net "FM_NMI_EVENT_N")
		)
		(pad "2" smd rect
			(at 0 0.889 180)
			(size 0.508 0.508)
			(layers "F.Cu" "F.Mask" "F.Paste")
			(net "FM_BMC_NMI_N")
		)
		(zone
			(layer "F.Cu")
			(hatch none 0.5)
			(connect_pads
				(clearance 0)
			)
			(min_thickness 0.25)
			(keepout
				(tracks not_allowed)
				(vias allowed)
				(pads allowed)
				(copperpour not_allowed)
				(footprints allowed)
			)
			(placement
				(enabled no)
				(sheetname "")
			)
			(fill
				(thermal_gap 0.5)
				(thermal_bridge_width 0.5)
				(island_removal_mode 0)
			)
			(polygon
				(pts
					(xy 396.621 -85.725) (xy 396.113 -85.725) (xy 396.113 -85.344) (xy 396.621 -85.344)
				)
			)
		)
		(zone
			(layer "F.Cu")
			(hatch none 0.5)
			(connect_pads
				(clearance 0)
			)
			(min_thickness 0.25)
			(keepout
				(tracks allowed)
				(vias not_allowed)
				(pads allowed)
				(copperpour not_allowed)
				(footprints allowed)
			)
			(placement
				(enabled no)
				(sheetname "")
			)
			(fill
				(thermal_gap 0.5)
				(thermal_bridge_width 0.5)
				(island_removal_mode 0)
			)
			(polygon
				(pts
					(xy 396.621 -85.344) (xy 396.113 -85.344) (xy 396.113 -85.725) (xy 396.621 -85.725)
				)
			)
		)
	)
	(footprint ""
		(layer "F.Cu")
		(at 40.60825 -102.729284 90)
		(property "Reference" "R1C7"
			(at -0.8382 -0.67818 90)
			(unlocked yes)
			(layer "F.SilkS")
			(effects
				(font
					(size 0.4064 0.254)
					(thickness 0.1524)
				)
				(justify left)
			)
		)
		(property "Value" ""
			(at 0 0 90)
			(layer "F.Fab")
			(effects
				(font
					(size 1.27 1.27)
				)
			)
		)
		(duplicate_pad_numbers_are_jumpers no)
		(fp_poly
			(pts
				(xy -0.2794 -0.1016) (xy 0.2794 -0.1016) (xy 0.2794 0.9906) (xy -0.2794 0.9906)
			)
			(stroke
				(width 0)
				(type default)
			)
			(fill no)
			(layer "F.CrtYd")
		)
		(fp_line
			(start 0.2794 -0.1016)
			(end -0.2794 -0.1016)
			(stroke
				(width 0.1)
				(type default)
			)
			(layer "F.Fab")
		)
		(fp_line
			(start -0.2794 -0.1016)
			(end -0.2794 0.9906)
			(stroke
				(width 0.1)
				(type default)
			)
			(layer "F.Fab")
		)
		(fp_line
			(start 0.2794 0.9906)
			(end 0.2794 -0.1016)
			(stroke
				(width 0.1)
				(type default)
			)
			(layer "F.Fab")
		)
		(fp_line
			(start -0.2794 0.9906)
			(end 0.2794 0.9906)
			(stroke
				(width 0.1)
				(type default)
			)
			(layer "F.Fab")
		)
		(pad "1" smd rect
			(at 0 0 90)
			(size 0.508 0.508)
			(layers "F.Cu" "F.Mask" "F.Paste")
			(net "VSENSE_PVSA_CPU1_P")
		)
		(pad "2" smd rect
			(at 0 0.889 90)
			(size 0.508 0.508)
			(layers "F.Cu" "F.Mask" "F.Paste")
			(net "VSENSE_PVSA_CPU1_SKT_VSEN")
		)
		(zone
			(layer "F.Cu")
			(hatch none 0.5)
			(connect_pads
				(clearance 0)
			)
			(min_thickness 0.25)
			(keepout
				(tracks allowed)
				(vias not_allowed)
				(pads allowed)
				(copperpour not_allowed)
				(footprints allowed)
			)
			(placement
				(enabled no)
				(sheetname "")
			)
			(fill
				(thermal_gap 0.5)
				(thermal_bridge_width 0.5)
				(island_removal_mode 0)
			)
			(polygon
				(pts
					(xy 40.86225 -102.475284) (xy 40.86225 -102.983284) (xy 41.24325 -102.983284) (xy 41.24325 -102.475284)
				)
			)
		)
		(zone
			(layer "F.Cu")
			(hatch none 0.5)
			(connect_pads
				(clearance 0)
			)
			(min_thickness 0.25)
			(keepout
				(tracks not_allowed)
				(vias allowed)
				(pads allowed)
				(copperpour not_allowed)
				(footprints allowed)
			)
			(placement
				(enabled no)
				(sheetname "")
			)
			(fill
				(thermal_gap 0.5)
				(thermal_bridge_width 0.5)
				(island_removal_mode 0)
			)
			(polygon
				(pts
					(xy 41.24325 -102.475284) (xy 41.24325 -102.983284) (xy 40.86225 -102.983284) (xy 40.86225 -102.475284)
				)
			)
		)
	)
	(footprint ""
		(layer "F.Cu")
		(at 477.901 -36.6395 180)
		(property "Reference" "R8G24"
			(at 0 0 180)
			(layer "F.SilkS")
			(hide yes)
			(effects
				(font
					(size 1.27 1.27)
				)
			)
		)
		(property "Value" ""
			(at 0 0 180)
			(layer "F.Fab")
			(effects
				(font
					(size 1.27 1.27)
				)
			)
		)
		(duplicate_pad_numbers_are_jumpers no)
		(fp_poly
			(pts
				(xy -0.2794 -0.1016) (xy 0.2794 -0.1016) (xy 0.2794 0.9906) (xy -0.2794 0.9906)
			)
			(stroke
				(width 0)
				(type default)
			)
			(fill no)
			(layer "F.CrtYd")
		)
		(fp_line
			(start 0.2794 0.9906)
			(end 0.2794 -0.1016)
			(stroke
				(width 0.1)
				(type default)
			)
			(layer "F.Fab")
		)
		(fp_line
			(start 0.2794 -0.1016)
			(end -0.2794 -0.1016)
			(stroke
				(width 0.1)
				(type default)
			)
			(layer "F.Fab")
		)
		(fp_line
			(start -0.2794 0.9906)
			(end 0.2794 0.9906)
			(stroke
				(width 0.1)
				(type default)
			)
			(layer "F.Fab")
		)
		(fp_line
			(start -0.2794 -0.1016)
			(end -0.2794 0.9906)
			(stroke
				(width 0.1)
				(type default)
			)
			(layer "F.Fab")
		)
		(pad "1" smd rect
			(at 0 0 180)
			(size 0.508 0.508)
			(layers "F.Cu" "F.Mask" "F.Paste")
			(net "CLK_50M_CKMNG_PCH_10GBE_R")
		)
		(pad "2" smd rect
			(at 0 0.889 180)
			(size 0.508 0.508)
			(layers "F.Cu" "F.Mask" "F.Paste")
			(net "CLK_50M_CKMNG_PCH_10GBE")
		)
		(zone
			(layer "F.Cu")
			(hatch none 0.5)
			(connect_pads
				(clearance 0)
			)
			(min_thickness 0.25)
			(keepout
				(tracks not_allowed)
				(vias allowed)
				(pads allowed)
				(copperpour not_allowed)
				(footprints allowed)
			)
			(placement
				(enabled no)
				(sheetname "")
			)
			(fill
				(thermal_gap 0.5)
				(thermal_bridge_width 0.5)
				(island_removal_mode 0)
			)
			(polygon
				(pts
					(xy 478.155 -37.2745) (xy 477.647 -37.2745) (xy 477.647 -36.8935) (xy 478.155 -36.8935)
				)
			)
		)
		(zone
			(layer "F.Cu")
			(hatch none 0.5)
			(connect_pads
				(clearance 0)
			)
			(min_thickness 0.25)
			(keepout
				(tracks allowed)
				(vias not_allowed)
				(pads allowed)
				(copperpour not_allowed)
				(footprints allowed)
			)
			(placement
				(enabled no)
				(sheetname "")
			)
			(fill
				(thermal_gap 0.5)
				(thermal_bridge_width 0.5)
				(island_removal_mode 0)
			)
			(polygon
				(pts
					(xy 478.155 -36.8935) (xy 477.647 -36.8935) (xy 477.647 -37.2745) (xy 478.155 -37.2745)
				)
			)
		)
	)
	(footprint ""
		(layer "F.Cu")
		(at 384.556 -87.3125 180)
		(property "Reference" "R7D10"
			(at 0 0 180)
			(layer "F.SilkS")
			(hide yes)
			(effects
				(font
					(size 1.27 1.27)
				)
			)
		)
		(property "Value" ""
			(at 0 0 180)
			(layer "F.Fab")
			(effects
				(font
					(size 1.27 1.27)
				)
			)
		)
		(duplicate_pad_numbers_are_jumpers no)
		(fp_poly
			(pts
				(xy -0.2794 -0.1016) (xy 0.2794 -0.1016) (xy 0.2794 0.9906) (xy -0.2794 0.9906)
			)
			(stroke
				(width 0)
				(type default)
			)
			(fill no)
			(layer "F.CrtYd")
		)
		(fp_line
			(start 0.2794 0.9906)
			(end 0.2794 -0.1016)
			(stroke
				(width 0.1)
				(type default)
			)
			(layer "F.Fab")
		)
		(fp_line
			(start 0.2794 -0.1016)
			(end -0.2794 -0.1016)
			(stroke
				(width 0.1)
				(type default)
			)
			(layer "F.Fab")
		)
		(fp_line
			(start -0.2794 0.9906)
			(end 0.2794 0.9906)
			(stroke
				(width 0.1)
				(type default)
			)
			(layer "F.Fab")
		)
		(fp_line
			(start -0.2794 -0.1016)
			(end -0.2794 0.9906)
			(stroke
				(width 0.1)
				(type default)
			)
			(layer "F.Fab")
		)
		(pad "1" smd rect
			(at 0 0 180)
			(size 0.508 0.508)
			(layers "F.Cu" "F.Mask" "F.Paste")
			(net "P3V3_STBY")
		)
		(pad "2" smd rect
			(at 0 0.889 180)
			(size 0.508 0.508)
			(layers "F.Cu" "F.Mask" "F.Paste")
			(net "PU_LPC_PME_N")
		)
		(zone
			(layer "F.Cu")
			(hatch none 0.5)
			(connect_pads
				(clearance 0)
			)
			(min_thickness 0.25)
			(keepout
				(tracks not_allowed)
				(vias allowed)
				(pads allowed)
				(copperpour not_allowed)
				(footprints allowed)
			)
			(placement
				(enabled no)
				(sheetname "")
			)
			(fill
				(thermal_gap 0.5)
				(thermal_bridge_width 0.5)
				(island_removal_mode 0)
			)
			(polygon
				(pts
					(xy 384.81 -87.9475) (xy 384.302 -87.9475) (xy 384.302 -87.5665) (xy 384.81 -87.5665)
				)
			)
		)
		(zone
			(layer "F.Cu")
			(hatch none 0.5)
			(connect_pads
				(clearance 0)
			)
			(min_thickness 0.25)
			(keepout
				(tracks allowed)
				(vias not_allowed)
				(pads allowed)
				(copperpour not_allowed)
				(footprints allowed)
			)
			(placement
				(enabled no)
				(sheetname "")
			)
			(fill
				(thermal_gap 0.5)
				(thermal_bridge_width 0.5)
				(island_removal_mode 0)
			)
			(polygon
				(pts
					(xy 384.81 -87.5665) (xy 384.302 -87.5665) (xy 384.302 -87.9475) (xy 384.81 -87.9475)
				)
			)
		)
	)
	(footprint ""
		(layer "F.Cu")
		(at 408.319478 -118.239032 90)
		(property "Reference" "R1W15"
			(at -0.8382 -0.67818 90)
			(unlocked yes)
			(layer "F.SilkS")
			(effects
				(font
					(size 0.4064 0.254)
					(thickness 0.1524)
				)
				(justify left)
			)
		)
		(property "Value" ""
			(at 0 0 90)
			(layer "F.Fab")
			(effects
				(font
					(size 1.27 1.27)
				)
			)
		)
		(duplicate_pad_numbers_are_jumpers no)
		(fp_poly
			(pts
				(xy -0.2794 -0.1016) (xy 0.2794 -0.1016) (xy 0.2794 0.9906) (xy -0.2794 0.9906)
			)
			(stroke
				(width 0)
				(type default)
			)
			(fill no)
			(layer "F.CrtYd")
		)
		(fp_line
			(start 0.2794 -0.1016)
			(end -0.2794 -0.1016)
			(stroke
				(width 0.1)
				(type default)
			)
			(layer "F.Fab")
		)
		(fp_line
			(start -0.2794 -0.1016)
			(end -0.2794 0.9906)
			(stroke
				(width 0.1)
				(type default)
			)
			(layer "F.Fab")
		)
		(fp_line
			(start 0.2794 0.9906)
			(end 0.2794 -0.1016)
			(stroke
				(width 0.1)
				(type default)
			)
			(layer "F.Fab")
		)
		(fp_line
			(start -0.2794 0.9906)
			(end 0.2794 0.9906)
			(stroke
				(width 0.1)
				(type default)
			)
			(layer "F.Fab")
		)
		(pad "1" smd rect
			(at 0 0 90)
			(size 0.508 0.508)
			(layers "F.Cu" "F.Mask" "F.Paste")
			(net "USB2_PCH_BMC_P5_DN_R")
		)
		(pad "2" smd rect
			(at 0 0.889 90)
			(size 0.508 0.508)
			(layers "F.Cu" "F.Mask" "F.Paste")
			(net "USB2_PCH_BMC_P5_DN")
		)
		(zone
			(layer "F.Cu")
			(hatch none 0.5)
			(connect_pads
				(clearance 0)
			)
			(min_thickness 0.25)
			(keepout
				(tracks allowed)
				(vias not_allowed)
				(pads allowed)
				(copperpour not_allowed)
				(footprints allowed)
			)
			(placement
				(enabled no)
				(sheetname "")
			)
			(fill
				(thermal_gap 0.5)
				(thermal_bridge_width 0.5)
				(island_removal_mode 0)
			)
			(polygon
				(pts
					(xy 408.573478 -117.985032) (xy 408.573478 -118.493032) (xy 408.954478 -118.493032) (xy 408.954478 -117.985032)
				)
			)
		)
		(zone
			(layer "F.Cu")
			(hatch none 0.5)
			(connect_pads
				(clearance 0)
			)
			(min_thickness 0.25)
			(keepout
				(tracks not_allowed)
				(vias allowed)
				(pads allowed)
				(copperpour not_allowed)
				(footprints allowed)
			)
			(placement
				(enabled no)
				(sheetname "")
			)
			(fill
				(thermal_gap 0.5)
				(thermal_bridge_width 0.5)
				(island_removal_mode 0)
			)
			(polygon
				(pts
					(xy 408.954478 -117.985032) (xy 408.954478 -118.493032) (xy 408.573478 -118.493032) (xy 408.573478 -117.985032)
				)
			)
		)
	)
	(footprint ""
		(layer "F.Cu")
		(at 332.5114 -140.9446 90)
		(property "Reference" "C6A5"
			(at 2.92862 3.24612 0)
			(unlocked yes)
			(layer "F.SilkS")
			(effects
				(font
					(size 0.4064 0.254)
					(thickness 0.1524)
				)
			)
		)
		(property "Value" ""
			(at 0 0 90)
			(layer "F.Fab")
			(effects
				(font
					(size 1.27 1.27)
				)
			)
		)
		(duplicate_pad_numbers_are_jumpers no)
		(fp_line
			(start 2.504948 -1.616456)
			(end 2.504948 1.633728)
			(stroke
				(width 0.1524)
				(type default)
			)
			(layer "F.SilkS")
		)
		(fp_line
			(start 1.6002 -1.616456)
			(end 2.504948 -1.616456)
			(stroke
				(width 0.1524)
				(type default)
			)
			(layer "F.SilkS")
		)
		(fp_line
			(start -1.6002 -1.616456)
			(end -2.563114 -1.616456)
			(stroke
				(width 0.1524)
				(type default)
			)
			(layer "F.SilkS")
		)
		(fp_line
			(start -2.563114 -1.616456)
			(end -2.563114 1.633728)
			(stroke
				(width 0.1524)
				(type default)
			)
			(layer "F.SilkS")
		)
		(fp_line
			(start 2.504948 1.633728)
			(end 1.6002 1.633728)
			(stroke
				(width 0.1524)
				(type default)
			)
			(layer "F.SilkS")
		)
		(fp_line
			(start -2.563114 1.633728)
			(end -1.6002 1.633728)
			(stroke
				(width 0.1524)
				(type default)
			)
			(layer "F.SilkS")
		)
		(fp_line
			(start 2.286 7.366)
			(end 2.286 1.63195)
			(stroke
				(width 0.1524)
				(type default)
			)
			(layer "F.SilkS")
		)
		(fp_line
			(start 2.286 7.366)
			(end 1.600708 7.366)
			(stroke
				(width 0.1524)
				(type default)
			)
			(layer "F.SilkS")
		)
		(fp_line
			(start -2.286 7.366)
			(end -2.286 1.632712)
			(stroke
				(width 0.1524)
				(type default)
			)
			(layer "F.SilkS")
		)
		(fp_line
			(start -2.286 7.366)
			(end -1.60147 7.366)
			(stroke
				(width 0.1524)
				(type default)
			)
			(layer "F.SilkS")
		)
		(fp_rect
			(start -2.286 7.366)
			(end 2.286 -0.254)
			(stroke
				(width 0)
				(type default)
			)
			(fill no)
			(layer "F.CrtYd")
		)
		(fp_line
			(start 2.286 -0.254)
			(end 2.286 7.366)
			(stroke
				(width 0.1)
				(type default)
			)
			(layer "F.Fab")
		)
		(fp_line
			(start -2.286 -0.254)
			(end 2.286 -0.254)
			(stroke
				(width 0.1)
				(type default)
			)
			(layer "F.Fab")
		)
		(fp_line
			(start 2.286 7.366)
			(end -2.286 7.366)
			(stroke
				(width 0.1)
				(type default)
			)
			(layer "F.Fab")
		)
		(fp_line
			(start -2.286 7.366)
			(end -2.286 -0.254)
			(stroke
				(width 0.1)
				(type default)
			)
			(layer "F.Fab")
		)
		(pad "1" smd rect
			(at 0 0 90)
			(size 2.54 3.048)
			(layers "F.Cu" "F.Mask" "F.Paste")
			(net "PVDDQ_DEF")
		)
		(pad "2" smd rect
			(at 0 7.112 90)
			(size 2.54 3.048)
			(layers "F.Cu" "F.Mask" "F.Paste")
			(net "GND")
		)
	)
)
